#ISCELL
  pure_quanta quanta_title_block_c *
  *
#ISCELL
  pure_quanta_power universal_power *
  page133_i18
#CELL
  pure_quanta q_res *
  page133_i19
#ISCELL
  pure_quanta_power universal_power *
  page133_i22
#CELL
  pure_quanta q_res *
  page133_i23
#CELL
  pure_quanta q_diode *
  page133_i24
#CELL
  pure_quanta q_diode *
  page133_i26
#CELL
  pure_quanta q_diode *
  page133_i37
#CELL
  pure_quanta q_diode *
  page133_i39
#CELL
  pure_quanta q_diode *
  page133_i40
#CELL
  pure_quanta q_diode *
  page133_i55
#ISCELL
  pure_quanta_power universal_gnd *
  page133_i67
#CELL
  pure_quanta sn74lvc1g07dbvr *
  page133_i68
#CELL
  pure_quanta q_cap *
  page133_i69
#ISCELL
  pure_quanta_power universal_power *
  page133_i70
#CELL
  pure_quanta q_res *
  page133_i71
#ISCELL
  pure_quanta_power universal_gnd *
  page133_i73
#ISCELL
  mstr_standard offpage *
  page133_i74
#ISCELL
  pure_quanta_power universal_power *
  page133_i75
#CELL
  pure_quanta q_res *
  page133_i76
#CELL
  pure_quanta q_res *
  page133_i77
#ISCELL
  pure_quanta_power universal_power *
  page133_i78
#CELL
  pure_quanta q_res *
  page133_i79
#ISCELL
  pure_quanta_power universal_power *
  page133_i80
#CELL
  pure_quanta q_res *
  page133_i81
#ISCELL
  pure_quanta_power universal_power *
  page133_i82
#CELL
  pure_quanta q_res *
  page133_i83
#ISCELL
  pure_quanta_power universal_power *
  page133_i84
#ISCELL
  standard offpage *
  page133_i85
#CELL
  pure_quanta q_res *
  page133_i86
#ISCELL
  standard offpage *
  page133_i87
#ISCELL
  standard offpage *
  page133_i88
#ISCELL
  standard offpage *
  page133_i89
#ISCELL
  standard offpage *
  page133_i90
#ISCELL
  standard offpage *
  page133_i91
#CELL
  pure_quanta q_res *
  page133_i92
#CELL
  pure_quanta q_res *
  page133_i93
#CELL
  pure_quanta q_res *
  page133_i94
#CELL
  pure_quanta q_res *
  page133_i95
#CELL
  pure_quanta q_res *
  page133_i96
